# T6G (Grand Teton) — schematic netlist excerpt (pin names and nets, part order shuffled) for the footprints in the layout excerpt that follows; sources: Cadence DE-HDL packaged netlist, KiCad conversion of 04192023_DAF0TMB3IC0_F0TG_MB_C_brd_V02_OCP.brd

PR237  Q_RES  0 5% CHIP  pkg 0402LF  page 54 : A = SVID_PVDDCR_CPU1_P1_SVD_R ; B = SVID_PVDDCR_CPU1_P1_SVD
C255  Q_CAP  22UF 4V 20% X6S  pkg C0402  page 323 : A = P0V9_CPU1_RT0_2A ; B = GND

(kicad_pcb
	(version 20260206)
	(generator "pcbnew")
	(generator_version "10.0")
	(general
		(thickness 1.6)
		(legacy_teardrops no)
	)
	(paper "A4")
	(title_block
		(title "04192023_DAF0TMB3IC0_F0TG_MB_C_brd_V02_OCP.brd")
		(comment 1 "Grand Teton / footprints 7258-7259 of 8354")
	)
	(layers
		(0 "F.Cu" signal "TOP")
		(4 "In1.Cu" signal "GND")
		(6 "In2.Cu" signal "IN1")
		(8 "In3.Cu" signal "GND1")
		(10 "In4.Cu" signal "IN2")
		(12 "In5.Cu" signal "GND2")
		(14 "In6.Cu" signal "IN3")
		(16 "In7.Cu" signal "GND3")
		(18 "In8.Cu" signal "VCC")
		(20 "In9.Cu" signal "VCC1")
		(22 "In10.Cu" signal "GND4")
		(24 "In11.Cu" signal "IN4")
		(26 "In12.Cu" signal "GND5")
		(28 "In13.Cu" signal "IN5")
		(30 "In14.Cu" signal "GND6")
		(32 "In15.Cu" signal "IN6")
		(34 "In16.Cu" signal "GND7")
		(2 "B.Cu" signal "BOTTOM")
		(9 "F.Adhes" user "F.Adhesive")
		(11 "B.Adhes" user "B.Adhesive")
		(13 "F.Paste" user "Package Geometry/Pastemask Top")
		(15 "B.Paste" user "Package Geometry/Pastemask Bottom")
		(5 "F.SilkS" user "Ref Des/Silkscreen Top")
		(7 "B.SilkS" user "Ref Des/Silkscreen Bottom")
		(1 "F.Mask" user "Board Geometry/Soldermask Top")
		(3 "B.Mask" user "Board Geometry/Soldermask Bottom")
		(17 "Dwgs.User" user "User.Drawings")
		(19 "Cmts.User" user "User.Comments")
		(21 "Eco1.User" user "User.Eco1")
		(23 "Eco2.User" user "User.Eco2")
		(25 "Edge.Cuts" user "Board Geometry/Outline")
		(27 "Margin" user)
		(31 "F.CrtYd" user "Package Geometry/Place Bound Top")
		(29 "B.CrtYd" user "Package Geometry/Place Bound Bottom")
		(35 "F.Fab" user "Ref Des/Assembly Top")
		(33 "B.Fab" user "Ref Des/Assembly Bottom")
	)
	(footprint ""
		(layer "B.Cu")
		(at 90.746834 -308.606952 90)
		(property "Reference" "PR237"
			(at 0 0 90)
			(layer "B.SilkS")
			(hide yes)
			(effects
				(font
					(size 1.27 1.27)
				)
				(justify mirror)
			)
		)
		(property "Value" ""
			(at 0 0 90)
			(layer "B.Fab")
			(effects
				(font
					(size 1.27 1.27)
				)
				(justify mirror)
			)
		)
		(duplicate_pad_numbers_are_jumpers no)
		(fp_line
			(start 0.7874 -0.4064)
			(end -0.7874 -0.4064)
			(stroke
				(width 0.1524)
				(type default)
			)
			(layer "B.SilkS")
		)
		(fp_line
			(start -0.7874 -0.4064)
			(end -0.7874 0.4064)
			(stroke
				(width 0.1524)
				(type default)
			)
			(layer "B.SilkS")
		)
		(fp_line
			(start 0.7874 0.4064)
			(end 0.7874 -0.4064)
			(stroke
				(width 0.1524)
				(type default)
			)
			(layer "B.SilkS")
		)
		(fp_line
			(start -0.7874 0.4064)
			(end 0.7874 0.4064)
			(stroke
				(width 0.1524)
				(type default)
			)
			(layer "B.SilkS")
		)
		(fp_line
			(start 0.67945 -0.305054)
			(end 0.12065 -0.305054)
			(stroke
				(width 0.1)
				(type default)
			)
			(layer "B.Fab")
		)
		(fp_line
			(start 0.12065 -0.305054)
			(end 0.12065 -0.2794)
			(stroke
				(width 0.1)
				(type default)
			)
			(layer "B.Fab")
		)
		(fp_line
			(start -0.12065 -0.3048)
			(end -0.67945 -0.3048)
			(stroke
				(width 0.1)
				(type default)
			)
			(layer "B.Fab")
		)
		(fp_line
			(start -0.67945 -0.3048)
			(end -0.67945 0.3048)
			(stroke
				(width 0.1)
				(type default)
			)
			(layer "B.Fab")
		)
		(fp_line
			(start 0.12065 -0.2794)
			(end -0.12065 -0.2794)
			(stroke
				(width 0.1)
				(type default)
			)
			(layer "B.Fab")
		)
		(fp_line
			(start -0.12065 -0.2794)
			(end -0.12065 -0.3048)
			(stroke
				(width 0.1)
				(type default)
			)
			(layer "B.Fab")
		)
		(fp_line
			(start 0.12065 0.2794)
			(end 0.12065 0.3048)
			(stroke
				(width 0.1)
				(type default)
			)
			(layer "B.Fab")
		)
		(fp_line
			(start -0.120396 0.2794)
			(end 0.12065 0.2794)
			(stroke
				(width 0.1)
				(type default)
			)
			(layer "B.Fab")
		)
		(fp_line
			(start 0.67945 0.3048)
			(end 0.67945 -0.305054)
			(stroke
				(width 0.1)
				(type default)
			)
			(layer "B.Fab")
		)
		(fp_line
			(start 0.12065 0.3048)
			(end 0.67945 0.3048)
			(stroke
				(width 0.1)
				(type default)
			)
			(layer "B.Fab")
		)
		(fp_line
			(start -0.120396 0.3048)
			(end -0.120396 0.2794)
			(stroke
				(width 0.1)
				(type default)
			)
			(layer "B.Fab")
		)
		(fp_line
			(start -0.67945 0.3048)
			(end -0.120396 0.3048)
			(stroke
				(width 0.1)
				(type default)
			)
			(layer "B.Fab")
		)
		(pad "1" smd circle
			(at 0.40005 0 270)
			(size 0 0)
			(layers "B.Cu" "B.Mask" "B.Paste")
			(net "SVID_PVDDCR_CPU1_P1_SVD_R")
		)
		(pad "2" smd circle
			(at -0.40005 0 270)
			(size 0 0)
			(layers "B.Cu" "B.Mask" "B.Paste")
			(net "SVID_PVDDCR_CPU1_P1_SVD")
		)
	)
	(footprint ""
		(layer "B.Cu")
		(at 52.191412 -390.560052 90)
		(property "Reference" "C255"
			(at 0 0 90)
			(layer "B.SilkS")
			(hide yes)
			(effects
				(font
					(size 1.27 1.27)
				)
				(justify mirror)
			)
		)
		(property "Value" ""
			(at 0 0 90)
			(layer "B.Fab")
			(effects
				(font
					(size 1.27 1.27)
				)
				(justify mirror)
			)
		)
		(duplicate_pad_numbers_are_jumpers no)
		(fp_line
			(start 0.7874 -0.4064)
			(end -0.7874 -0.4064)
			(stroke
				(width 0.1524)
				(type default)
			)
			(layer "B.SilkS")
		)
		(fp_line
			(start -0.7874 -0.4064)
			(end -0.7874 0.4064)
			(stroke
				(width 0.1524)
				(type default)
			)
			(layer "B.SilkS")
		)
		(fp_line
			(start 0.7874 0.4064)
			(end 0.7874 -0.4064)
			(stroke
				(width 0.1524)
				(type default)
			)
			(layer "B.SilkS")
		)
		(fp_line
			(start -0.7874 0.4064)
			(end 0.7874 0.4064)
			(stroke
				(width 0.1524)
				(type default)
			)
			(layer "B.SilkS")
		)
		(fp_line
			(start 0.67945 -0.305054)
			(end 0.12065 -0.305054)
			(stroke
				(width 0.1)
				(type default)
			)
			(layer "B.Fab")
		)
		(fp_line
			(start 0.12065 -0.305054)
			(end 0.12065 -0.2794)
			(stroke
				(width 0.1)
				(type default)
			)
			(layer "B.Fab")
		)
		(fp_line
			(start -0.12065 -0.3048)
			(end -0.67945 -0.3048)
			(stroke
				(width 0.1)
				(type default)
			)
			(layer "B.Fab")
		)
		(fp_line
			(start -0.67945 -0.3048)
			(end -0.67945 0.3048)
			(stroke
				(width 0.1)
				(type default)
			)
			(layer "B.Fab")
		)
		(fp_line
			(start 0.12065 -0.2794)
			(end -0.12065 -0.2794)
			(stroke
				(width 0.1)
				(type default)
			)
			(layer "B.Fab")
		)
		(fp_line
			(start -0.12065 -0.2794)
			(end -0.12065 -0.3048)
			(stroke
				(width 0.1)
				(type default)
			)
			(layer "B.Fab")
		)
		(fp_line
			(start 0.12065 0.2794)
			(end 0.12065 0.3048)
			(stroke
				(width 0.1)
				(type default)
			)
			(layer "B.Fab")
		)
		(fp_line
			(start -0.120396 0.2794)
			(end 0.12065 0.2794)
			(stroke
				(width 0.1)
				(type default)
			)
			(layer "B.Fab")
		)
		(fp_line
			(start 0.67945 0.3048)
			(end 0.67945 -0.305054)
			(stroke
				(width 0.1)
				(type default)
			)
			(layer "B.Fab")
		)
		(fp_line
			(start 0.12065 0.3048)
			(end 0.67945 0.3048)
			(stroke
				(width 0.1)
				(type default)
			)
			(layer "B.Fab")
		)
		(fp_line
			(start -0.120396 0.3048)
			(end -0.120396 0.2794)
			(stroke
				(width 0.1)
				(type default)
			)
			(layer "B.Fab")
		)
		(fp_line
			(start -0.67945 0.3048)
			(end -0.120396 0.3048)
			(stroke
				(width 0.1)
				(type default)
			)
			(layer "B.Fab")
		)
		(pad "1" smd circle
			(at 0.40005 0 270)
			(size 0 0)
			(layers "B.Cu" "B.Mask" "B.Paste")
			(net "P0V9_CPU1_RT0_2A")
		)
		(pad "2" smd circle
			(at -0.40005 0 270)
			(size 0 0)
			(layers "B.Cu" "B.Mask" "B.Paste")
			(net "GND")
		)
	)
)
